# S9S_MB_2U (Grand Teton) — schematic netlist excerpt (pin names and nets, part order shuffled) for the footprints in the layout excerpt that follows; sources: Cadence DE-HDL packaged netlist, KiCad conversion of 03242023_DA0F0TMBIJ0_F0T_Motherboard_J_brd_V01_OCP.brd

C324  Q_CAP  47UF 4V 20% X6S  pkg C0805  page 78 : A = PVCCIN_CPU1 ; B = GND

X28  TP_TDR_4P_FTS  TP_TDR_4P_DIP EMPTY  pkg TH  page 309
  S1  = TDR_DIFF_85_IN6_DN
  P1  = T1_GND
  P2  = T1_GND
  S2  = TDR_DIFF_85_IN6_DP

(kicad_pcb
	(version 20260206)
	(generator "pcbnew")
	(generator_version "10.0")
	(general
		(thickness 1.6)
		(legacy_teardrops no)
	)
	(paper "A4")
	(title_block
		(title "03242023_DA0F0TMBIJ0_F0T_Motherboard_J_brd_V01_OCP.brd")
		(comment 1 "Grand Teton / footprints 5175-5176 of 6105")
	)
	(layers
		(0 "F.Cu" signal "TOP")
		(4 "In1.Cu" signal "GND")
		(6 "In2.Cu" signal "IN1")
		(8 "In3.Cu" signal "GND1")
		(10 "In4.Cu" signal "IN2")
		(12 "In5.Cu" signal "GND2")
		(14 "In6.Cu" signal "IN3")
		(16 "In7.Cu" signal "GND3")
		(18 "In8.Cu" signal "VCC")
		(20 "In9.Cu" signal "VCC1")
		(22 "In10.Cu" signal "GND4")
		(24 "In11.Cu" signal "IN4")
		(26 "In12.Cu" signal "GND5")
		(28 "In13.Cu" signal "IN5")
		(30 "In14.Cu" signal "GND6")
		(32 "In15.Cu" signal "IN6")
		(34 "In16.Cu" signal "GND7")
		(2 "B.Cu" signal "BOTTOM")
		(9 "F.Adhes" user "F.Adhesive")
		(11 "B.Adhes" user "B.Adhesive")
		(13 "F.Paste" user "Package Geometry/Pastemask Top")
		(15 "B.Paste" user "Package Geometry/Pastemask Bottom")
		(5 "F.SilkS" user "Ref Des/Silkscreen Top")
		(7 "B.SilkS" user "Ref Des/Silkscreen Bottom")
		(1 "F.Mask" user "Board Geometry/Soldermask Top")
		(3 "B.Mask" user "Board Geometry/Soldermask Bottom")
		(17 "Dwgs.User" user "User.Drawings")
		(19 "Cmts.User" user "User.Comments")
		(21 "Eco1.User" user "User.Eco1")
		(23 "Eco2.User" user "User.Eco2")
		(25 "Edge.Cuts" user "Board Geometry/Outline")
		(27 "Margin" user)
		(31 "F.CrtYd" user "Package Geometry/Place Bound Top")
		(29 "B.CrtYd" user "Package Geometry/Place Bound Bottom")
		(35 "F.Fab" user "Ref Des/Assembly Top")
		(33 "B.Fab" user "Ref Des/Assembly Bottom")
	)
	(footprint ""
		(layer "B.Cu")
		(at 107.457494 -255.8542 -90)
		(property "Reference" "C324"
			(at 0 0 90)
			(layer "B.SilkS")
			(hide yes)
			(effects
				(font
					(size 1.27 1.27)
				)
				(justify mirror)
			)
		)
		(property "Value" ""
			(at 0 0 90)
			(layer "B.Fab")
			(effects
				(font
					(size 1.27 1.27)
				)
				(justify mirror)
			)
		)
		(duplicate_pad_numbers_are_jumpers no)
		(fp_line
			(start -1.524 0.762)
			(end 1.524 0.762)
			(stroke
				(width 0.1524)
				(type default)
			)
			(layer "B.SilkS")
		)
		(fp_line
			(start 1.524 0.762)
			(end 1.524 -0.762)
			(stroke
				(width 0.1524)
				(type default)
			)
			(layer "B.SilkS")
		)
		(fp_line
			(start -1.524 -0.762)
			(end -1.524 0.762)
			(stroke
				(width 0.1524)
				(type default)
			)
			(layer "B.SilkS")
		)
		(fp_line
			(start 1.524 -0.762)
			(end -1.524 -0.762)
			(stroke
				(width 0.1524)
				(type default)
			)
			(layer "B.SilkS")
		)
		(fp_line
			(start -1.1049 0.724916)
			(end -1.1049 -0.724916)
			(stroke
				(width 0.1)
				(type default)
			)
			(layer "B.Fab")
		)
		(fp_line
			(start 1.1049 0.724916)
			(end -1.1049 0.724916)
			(stroke
				(width 0.1)
				(type default)
			)
			(layer "B.Fab")
		)
		(fp_line
			(start -1.1049 -0.724916)
			(end 1.1049 -0.724916)
			(stroke
				(width 0.1)
				(type default)
			)
			(layer "B.Fab")
		)
		(fp_line
			(start 1.1049 -0.724916)
			(end 1.1049 0.724916)
			(stroke
				(width 0.1)
				(type default)
			)
			(layer "B.Fab")
		)
		(pad "1" smd rect
			(at 0.889 0 270)
			(size 1.016 1.27)
			(layers "B.Cu" "B.Mask" "B.Paste")
			(net "PVCCIN_CPU1")
		)
		(pad "2" smd rect
			(at -0.889 0 270)
			(size 1.016 1.27)
			(layers "B.Cu" "B.Mask" "B.Paste")
			(net "GND")
		)
	)
	(footprint ""
		(layer "B.Cu")
		(at 498.693948 -153.16454 90)
		(property "Reference" "X28"
			(at 1.46177 2.60096 270)
			(unlocked yes)
			(layer "B.SilkS")
			(effects
				(font
					(size 0.7874 0.5842)
					(thickness 0.1524)
				)
				(justify left mirror)
			)
		)
		(property "Value" ""
			(at 0 0 90)
			(layer "B.Fab")
			(effects
				(font
					(size 1.27 1.27)
				)
				(justify mirror)
			)
		)
		(property "Device Type" "TP_TDR_4P_FTS_TH-TP_TDR_4P_DIPA"
			(at -1.30175 1.27 0)
			(unlocked yes)
			(layer "B.Fab")
			(hide yes)
			(effects
				(font
					(size 0.635 0.4064)
					(thickness 0.1524)
				)
				(justify mirror)
			)
		)
		(property "User Part Number" "N_A"
			(at -1.30175 1.27 0)
			(unlocked yes)
			(layer "Cmts.User")
			(hide yes)
			(effects
				(font
					(size 0.635 0.4064)
					(thickness 0.1524)
				)
				(justify mirror)
			)
		)
		(duplicate_pad_numbers_are_jumpers no)
		(fp_line
			(start 0 -1.27)
			(end 0 -0.635)
			(stroke
				(width 0.1524)
				(type default)
			)
			(layer "B.SilkS")
		)
		(fp_line
			(start -2.54 -1.27)
			(end 0 -1.27)
			(stroke
				(width 0.1524)
				(type default)
			)
			(layer "B.SilkS")
		)
		(fp_line
			(start -2.54 -1.1303)
			(end -2.54 -1.27)
			(stroke
				(width 0.1524)
				(type default)
			)
			(layer "B.SilkS")
		)
		(fp_line
			(start 0 0.635)
			(end 0 1.905)
			(stroke
				(width 0.1524)
				(type default)
			)
			(layer "B.SilkS")
		)
		(fp_line
			(start -2.54 1.4097)
			(end -2.54 1.1303)
			(stroke
				(width 0.1524)
				(type default)
			)
			(layer "B.SilkS")
		)
		(fp_line
			(start 0 3.175)
			(end 0 3.81)
			(stroke
				(width 0.1524)
				(type default)
			)
			(layer "B.SilkS")
		)
		(fp_line
			(start 0 3.81)
			(end -2.54 3.81)
			(stroke
				(width 0.1524)
				(type default)
			)
			(layer "B.SilkS")
		)
		(fp_line
			(start -2.54 3.81)
			(end -2.54 3.6703)
			(stroke
				(width 0.1524)
				(type default)
			)
			(layer "B.SilkS")
		)
		(fp_poly
			(pts
				(xy 2.790952 -0.930402) (xy 2.790952 0.593598) (xy 1.266952 -0.168402)
			)
			(stroke
				(width 0)
				(type default)
			)
			(fill yes)
			(layer "B.SilkS")
		)
		(fp_line
			(start 0 -1.27)
			(end 0 3.81)
			(stroke
				(width 0.1)
				(type default)
			)
			(layer "B.Fab")
		)
		(fp_line
			(start -2.54 -1.27)
			(end 0 -1.27)
			(stroke
				(width 0.1)
				(type default)
			)
			(layer "B.Fab")
		)
		(fp_line
			(start 0 3.81)
			(end -2.54 3.81)
			(stroke
				(width 0.1)
				(type default)
			)
			(layer "B.Fab")
		)
		(fp_line
			(start -2.54 3.81)
			(end -2.54 -1.27)
			(stroke
				(width 0.1)
				(type default)
			)
			(layer "B.Fab")
		)
		(fp_poly
			(pts
				(xy 0.761746 0) (xy 2.285746 -0.762) (xy 2.285746 0.762)
			)
			(stroke
				(width 0)
				(type default)
			)
			(fill yes)
			(layer "B.Fab")
		)
		(pad "1" thru_hole circle
			(at 0 0 270)
			(size 1.0033 1.0033)
			(drill 0.249936)
			(layers "*.Cu" "*.Mask")
			(remove_unused_layers no)
			(net "TDR_DIFF_85_IN6_DN")
			(clearance 0.10795)
			(padstack
				(mode front_inner_back)
				(layer "Inner"
					(shape circle)
					(size 0.8001 0.8001)
					(clearance 0.1524)
				)
				(layer "B.Cu"
					(shape circle)
					(size 1.0033 1.0033)
					(thermal_gap 0.10795)
					(clearance 0.10795)
				)
			)
		)
		(pad "2" thru_hole circle
			(at -2.54 0 270)
			(size 1.9939 1.9939)
			(drill 0.249936)
			(layers "*.Cu" "*.Mask")
			(remove_unused_layers no)
			(net "T1_GND")
			(clearance 0.10795)
			(padstack
				(mode front_inner_back)
				(layer "Inner"
					(shape circle)
					(size 0.8001 0.8001)
					(clearance 0.1524)
				)
				(layer "B.Cu"
					(shape circle)
					(size 1.9939 1.9939)
					(thermal_gap 0.10795)
					(clearance 0.10795)
				)
			)
		)
		(pad "3" thru_hole circle
			(at -2.54 2.54 270)
			(size 1.9939 1.9939)
			(drill 0.249936)
			(layers "*.Cu" "*.Mask")
			(remove_unused_layers no)
			(net "T1_GND")
			(clearance 0.10795)
			(padstack
				(mode front_inner_back)
				(layer "Inner"
					(shape circle)
					(size 0.8001 0.8001)
					(clearance 0.1524)
				)
				(layer "B.Cu"
					(shape circle)
					(size 1.9939 1.9939)
					(thermal_gap 0.10795)
					(clearance 0.10795)
				)
			)
		)
		(pad "4" thru_hole circle
			(at 0 2.54 270)
			(size 1.0033 1.0033)
			(drill 0.249936)
			(layers "*.Cu" "*.Mask")
			(remove_unused_layers no)
			(net "TDR_DIFF_85_IN6_DP")
			(clearance 0.10795)
			(padstack
				(mode front_inner_back)
				(layer "Inner"
					(shape circle)
					(size 0.8001 0.8001)
					(clearance 0.1524)
				)
				(layer "B.Cu"
					(shape circle)
					(size 1.0033 1.0033)
					(thermal_gap 0.10795)
					(clearance 0.10795)
				)
			)
		)
	)
)
